(kicad_pcb
	(version 20260206)
	(generator "pcbnew")
	(generator_version "10.0")
	(general
		(thickness 1.6)
		(legacy_teardrops no)
	)
	(paper "A4")
	(title_block
		(title "12092022_DA0F0TMDCD0_F0T_Management_Board_D_brd_V3_OCP.brd")
		(comment 1 "Grand Teton / footprints 672-677 of 1440")
	)
	(layers
		(0 "F.Cu" signal "TOP")
		(4 "In1.Cu" signal "GND")
		(6 "In2.Cu" signal "IN1")
		(8 "In3.Cu" signal "GND1")
		(10 "In4.Cu" signal "IN2")
		(12 "In5.Cu" signal "VCC")
		(14 "In6.Cu" signal "VCC1")
		(16 "In7.Cu" signal "IN3")
		(18 "In8.Cu" signal "GND2")
		(20 "In9.Cu" signal "IN4")
		(22 "In10.Cu" signal "GND3")
		(2 "B.Cu" signal "BOTTOM")
		(9 "F.Adhes" user "F.Adhesive")
		(11 "B.Adhes" user "B.Adhesive")
		(13 "F.Paste" user "Package Geometry/Pastemask Top")
		(15 "B.Paste" user "Package Geometry/Pastemask Bottom")
		(5 "F.SilkS" user "Ref Des/Silkscreen Top")
		(7 "B.SilkS" user "Ref Des/Silkscreen Bottom")
		(1 "F.Mask" user "Board Geometry/Soldermask Top")
		(3 "B.Mask" user "Board Geometry/Soldermask Bottom")
		(17 "Dwgs.User" user "User.Drawings")
		(19 "Cmts.User" user "User.Comments")
		(21 "Eco1.User" user "User.Eco1")
		(23 "Eco2.User" user "User.Eco2")
		(25 "Edge.Cuts" user "Board Geometry/Outline")
		(27 "Margin" user)
		(31 "F.CrtYd" user "Package Geometry/Place Bound Top")
		(29 "B.CrtYd" user "Package Geometry/Place Bound Bottom")
		(35 "F.Fab" user "Ref Des/Assembly Top")
		(33 "B.Fab" user "Ref Des/Assembly Bottom")
	)
	(footprint ""
		(layer "F.Cu")
		(at 42.3418 -26.2636)
		(property "Reference" "U28"
			(at 0.573278 -2.323846 0)
			(unlocked yes)
			(layer "F.SilkS")
			(effects
				(font
					(size 0.7874 0.5842)
					(thickness 0.1524)
				)
				(justify left)
			)
		)
		(property "Value" ""
			(at 0 0 0)
			(layer "F.Fab")
			(effects
				(font
					(size 1.27 1.27)
				)
			)
		)
		(duplicate_pad_numbers_are_jumpers no)
		(fp_line
			(start -2.032 -1.549908)
			(end 2.032 -1.549908)
			(stroke
				(width 0.1524)
				(type default)
			)
			(layer "F.SilkS")
		)
		(fp_line
			(start -2.032 1.549908)
			(end -2.032 -1.549908)
			(stroke
				(width 0.1524)
				(type default)
			)
			(layer "F.SilkS")
		)
		(fp_line
			(start 2.032 -1.549908)
			(end 2.032 1.549908)
			(stroke
				(width 0.1524)
				(type default)
			)
			(layer "F.SilkS")
		)
		(fp_line
			(start 2.032 1.549908)
			(end -2.032 1.549908)
			(stroke
				(width 0.1524)
				(type default)
			)
			(layer "F.SilkS")
		)
		(fp_poly
			(pts
				(xy -2.9464 -1.2192) (xy -2.9464 -0.7112) (xy -2.1844 -0.9652)
			)
			(stroke
				(width 0)
				(type default)
			)
			(fill yes)
			(layer "F.SilkS")
		)
		(fp_line
			(start -0.849884 -1.549908)
			(end -0.849884 1.549908)
			(stroke
				(width 0.1)
				(type default)
			)
			(layer "F.Fab")
		)
		(fp_line
			(start -0.849884 1.549908)
			(end 0.849884 1.549908)
			(stroke
				(width 0.1)
				(type default)
			)
			(layer "F.Fab")
		)
		(fp_line
			(start 0.849884 -1.549908)
			(end -0.849884 -1.549908)
			(stroke
				(width 0.1)
				(type default)
			)
			(layer "F.Fab")
		)
		(fp_line
			(start 0.849884 1.549908)
			(end 0.849884 -1.549908)
			(stroke
				(width 0.1)
				(type default)
			)
			(layer "F.Fab")
		)
		(fp_poly
			(pts
				(xy -2.9464 -1.2192) (xy -2.9464 -0.7112) (xy -2.1844 -0.9652)
			)
			(stroke
				(width 0)
				(type default)
			)
			(fill yes)
			(layer "F.Fab")
		)
		(pad "1" smd rect
			(at -1.225042 -0.94996 270)
			(size 0.4572 1.3208)
			(layers "F.Cu" "F.Mask" "F.Paste")
			(net "RMII_OCP_RCLKI")
		)
		(pad "2" smd rect
			(at -1.225042 0 270)
			(size 0.4572 1.3208)
			(layers "F.Cu" "F.Mask" "F.Paste")
			(net "RMII_OCP_RCLKI_ISO")
		)
		(pad "3" smd rect
			(at -1.225042 0.94996 270)
			(size 0.4572 1.3208)
			(layers "F.Cu" "F.Mask" "F.Paste")
			(net "GND")
		)
		(pad "4" smd rect
			(at 1.225042 0.94996 270)
			(size 0.4572 1.3208)
			(layers "F.Cu" "F.Mask" "F.Paste")
			(net "PWRGD_P1V0_AUX_DELAY_R")
		)
		(pad "5" smd rect
			(at 1.225042 -0.94996 270)
			(size 0.4572 1.3208)
			(layers "F.Cu" "F.Mask" "F.Paste")
			(net "P3V3_LDO")
		)
	)
	(footprint ""
		(layer "F.Cu")
		(at 40.887142 -63.756794 -90)
		(property "Reference" "R185"
			(at 0 0 270)
			(layer "F.SilkS")
			(hide yes)
			(effects
				(font
					(size 1.27 1.27)
				)
			)
		)
		(property "Value" ""
			(at 0 0 270)
			(layer "F.Fab")
			(effects
				(font
					(size 1.27 1.27)
				)
			)
		)
		(duplicate_pad_numbers_are_jumpers no)
		(fp_line
			(start -0.7874 0.4064)
			(end -0.7874 -0.4064)
			(stroke
				(width 0.1524)
				(type default)
			)
			(layer "F.SilkS")
		)
		(fp_line
			(start 0.7874 0.4064)
			(end -0.7874 0.4064)
			(stroke
				(width 0.1524)
				(type default)
			)
			(layer "F.SilkS")
		)
		(fp_line
			(start -0.7874 -0.4064)
			(end 0.7874 -0.4064)
			(stroke
				(width 0.1524)
				(type default)
			)
			(layer "F.SilkS")
		)
		(fp_line
			(start 0.7874 -0.4064)
			(end 0.7874 0.4064)
			(stroke
				(width 0.1524)
				(type default)
			)
			(layer "F.SilkS")
		)
		(fp_line
			(start -0.67945 0.3048)
			(end -0.67945 -0.305054)
			(stroke
				(width 0.1)
				(type default)
			)
			(layer "F.Fab")
		)
		(fp_line
			(start -0.12065 0.3048)
			(end -0.67945 0.3048)
			(stroke
				(width 0.1)
				(type default)
			)
			(layer "F.Fab")
		)
		(fp_line
			(start 0.120396 0.3048)
			(end 0.120396 0.2794)
			(stroke
				(width 0.1)
				(type default)
			)
			(layer "F.Fab")
		)
		(fp_line
			(start 0.67945 0.3048)
			(end 0.120396 0.3048)
			(stroke
				(width 0.1)
				(type default)
			)
			(layer "F.Fab")
		)
		(fp_line
			(start -0.12065 0.2794)
			(end -0.12065 0.3048)
			(stroke
				(width 0.1)
				(type default)
			)
			(layer "F.Fab")
		)
		(fp_line
			(start 0.120396 0.2794)
			(end -0.12065 0.2794)
			(stroke
				(width 0.1)
				(type default)
			)
			(layer "F.Fab")
		)
		(fp_line
			(start -0.12065 -0.2794)
			(end 0.12065 -0.2794)
			(stroke
				(width 0.1)
				(type default)
			)
			(layer "F.Fab")
		)
		(fp_line
			(start 0.12065 -0.2794)
			(end 0.12065 -0.3048)
			(stroke
				(width 0.1)
				(type default)
			)
			(layer "F.Fab")
		)
		(fp_line
			(start 0.12065 -0.3048)
			(end 0.67945 -0.3048)
			(stroke
				(width 0.1)
				(type default)
			)
			(layer "F.Fab")
		)
		(fp_line
			(start 0.67945 -0.3048)
			(end 0.67945 0.3048)
			(stroke
				(width 0.1)
				(type default)
			)
			(layer "F.Fab")
		)
		(fp_line
			(start -0.67945 -0.305054)
			(end -0.12065 -0.305054)
			(stroke
				(width 0.1)
				(type default)
			)
			(layer "F.Fab")
		)
		(fp_line
			(start -0.12065 -0.305054)
			(end -0.12065 -0.2794)
			(stroke
				(width 0.1)
				(type default)
			)
			(layer "F.Fab")
		)
		(pad "1" smd circle
			(at -0.40005 0 270)
			(size 0 0)
			(layers "F.Cu" "F.Mask" "F.Paste")
			(net "I3C1_SPD_SDA")
		)
		(pad "2" smd circle
			(at 0.40005 0 270)
			(size 0 0)
			(layers "F.Cu" "F.Mask" "F.Paste")
			(net "I3C1_SDA_R")
		)
	)
	(footprint ""
		(layer "F.Cu")
		(at 13.335 -16.383 90)
		(property "Reference" "R619"
			(at 0 0 90)
			(layer "F.SilkS")
			(hide yes)
			(effects
				(font
					(size 1.27 1.27)
				)
			)
		)
		(property "Value" ""
			(at 0 0 90)
			(layer "F.Fab")
			(effects
				(font
					(size 1.27 1.27)
				)
			)
		)
		(duplicate_pad_numbers_are_jumpers no)
		(fp_line
			(start 0.7874 -0.4064)
			(end 0.7874 0.4064)
			(stroke
				(width 0.1524)
				(type default)
			)
			(layer "F.SilkS")
		)
		(fp_line
			(start -0.7874 -0.4064)
			(end 0.7874 -0.4064)
			(stroke
				(width 0.1524)
				(type default)
			)
			(layer "F.SilkS")
		)
		(fp_line
			(start 0.7874 0.4064)
			(end -0.7874 0.4064)
			(stroke
				(width 0.1524)
				(type default)
			)
			(layer "F.SilkS")
		)
		(fp_line
			(start -0.7874 0.4064)
			(end -0.7874 -0.4064)
			(stroke
				(width 0.1524)
				(type default)
			)
			(layer "F.SilkS")
		)
		(fp_line
			(start -0.12065 -0.305054)
			(end -0.12065 -0.2794)
			(stroke
				(width 0.1)
				(type default)
			)
			(layer "F.Fab")
		)
		(fp_line
			(start -0.67945 -0.305054)
			(end -0.12065 -0.305054)
			(stroke
				(width 0.1)
				(type default)
			)
			(layer "F.Fab")
		)
		(fp_line
			(start 0.67945 -0.3048)
			(end 0.67945 0.3048)
			(stroke
				(width 0.1)
				(type default)
			)
			(layer "F.Fab")
		)
		(fp_line
			(start 0.12065 -0.3048)
			(end 0.67945 -0.3048)
			(stroke
				(width 0.1)
				(type default)
			)
			(layer "F.Fab")
		)
		(fp_line
			(start 0.12065 -0.2794)
			(end 0.12065 -0.3048)
			(stroke
				(width 0.1)
				(type default)
			)
			(layer "F.Fab")
		)
		(fp_line
			(start -0.12065 -0.2794)
			(end 0.12065 -0.2794)
			(stroke
				(width 0.1)
				(type default)
			)
			(layer "F.Fab")
		)
		(fp_line
			(start 0.120396 0.2794)
			(end -0.12065 0.2794)
			(stroke
				(width 0.1)
				(type default)
			)
			(layer "F.Fab")
		)
		(fp_line
			(start -0.12065 0.2794)
			(end -0.12065 0.3048)
			(stroke
				(width 0.1)
				(type default)
			)
			(layer "F.Fab")
		)
		(fp_line
			(start 0.67945 0.3048)
			(end 0.120396 0.3048)
			(stroke
				(width 0.1)
				(type default)
			)
			(layer "F.Fab")
		)
		(fp_line
			(start 0.120396 0.3048)
			(end 0.120396 0.2794)
			(stroke
				(width 0.1)
				(type default)
			)
			(layer "F.Fab")
		)
		(fp_line
			(start -0.12065 0.3048)
			(end -0.67945 0.3048)
			(stroke
				(width 0.1)
				(type default)
			)
			(layer "F.Fab")
		)
		(fp_line
			(start -0.67945 0.3048)
			(end -0.67945 -0.305054)
			(stroke
				(width 0.1)
				(type default)
			)
			(layer "F.Fab")
		)
		(pad "1" smd circle
			(at -0.40005 0 90)
			(size 0 0)
			(layers "F.Cu" "F.Mask" "F.Paste")
			(net "HDD_LED_N")
		)
		(pad "2" smd circle
			(at 0.40005 0 90)
			(size 0 0)
			(layers "F.Cu" "F.Mask" "F.Paste")
			(net "GND")
		)
	)
	(footprint ""
		(layer "F.Cu")
		(at 43.45559 -22.159976)
		(property "Reference" "L22"
			(at 0 0 0)
			(layer "F.SilkS")
			(hide yes)
			(effects
				(font
					(size 1.27 1.27)
				)
			)
		)
		(property "Value" ""
			(at 0 0 0)
			(layer "F.Fab")
			(effects
				(font
					(size 1.27 1.27)
				)
			)
		)
		(duplicate_pad_numbers_are_jumpers no)
		(fp_line
			(start -0.8636 -1.524)
			(end -0.379984 -1.524)
			(stroke
				(width 0.1524)
				(type default)
			)
			(layer "F.SilkS")
		)
		(fp_line
			(start -0.8636 1.524)
			(end -0.8636 -1.524)
			(stroke
				(width 0.1524)
				(type default)
			)
			(layer "F.SilkS")
		)
		(fp_line
			(start -0.425704 1.524)
			(end -0.8636 1.524)
			(stroke
				(width 0.1524)
				(type default)
			)
			(layer "F.SilkS")
		)
		(fp_line
			(start 0.425196 -1.524)
			(end 0.8636 -1.524)
			(stroke
				(width 0.1524)
				(type default)
			)
			(layer "F.SilkS")
		)
		(fp_line
			(start 0.8636 -1.524)
			(end 0.8636 1.524)
			(stroke
				(width 0.1524)
				(type default)
			)
			(layer "F.SilkS")
		)
		(fp_line
			(start 0.8636 1.524)
			(end 0.511556 1.524)
			(stroke
				(width 0.1524)
				(type default)
			)
			(layer "F.SilkS")
		)
		(fp_poly
			(pts
				(xy -0.922528 -1.650746) (xy -1.461262 -1.830324) (xy -1.102106 -2.18948)
			)
			(stroke
				(width 0)
				(type default)
			)
			(fill yes)
			(layer "F.SilkS")
		)
		(fp_line
			(start -0.700024 -1.100074)
			(end 0.700024 -1.100074)
			(stroke
				(width 0.1)
				(type default)
			)
			(layer "F.Fab")
		)
		(fp_line
			(start -0.700024 1.100074)
			(end -0.700024 -1.100074)
			(stroke
				(width 0.1)
				(type default)
			)
			(layer "F.Fab")
		)
		(fp_line
			(start 0.700024 -1.100074)
			(end 0.700024 1.100074)
			(stroke
				(width 0.1)
				(type default)
			)
			(layer "F.Fab")
		)
		(fp_line
			(start 0.700024 1.100074)
			(end -0.700024 1.100074)
			(stroke
				(width 0.1)
				(type default)
			)
			(layer "F.Fab")
		)
		(fp_poly
			(pts
				(xy -0.4572 -1.6256) (xy -0.7112 -2.1336) (xy -0.2032 -2.1336)
			)
			(stroke
				(width 0)
				(type default)
			)
			(fill yes)
			(layer "F.Fab")
		)
		(pad "1" smd rect
			(at -0.424942 -0.849884)
			(size 0.3556 0.9144)
			(layers "F.Cu" "F.Mask" "F.Paste")
			(net "USB3_01_MUX_FB_RXP")
		)
		(pad "2" smd rect
			(at -0.424942 0.849884)
			(size 0.3556 0.9144)
			(layers "F.Cu" "F.Mask" "F.Paste")
			(net "USB3_01_FB_RXP")
		)
		(pad "3" smd rect
			(at 0.424942 0.849884)
			(size 0.3556 0.9144)
			(layers "F.Cu" "F.Mask" "F.Paste")
			(net "USB3_01_FB_RXN")
		)
		(pad "4" smd rect
			(at 0.424942 -0.849884)
			(size 0.3556 0.9144)
			(layers "F.Cu" "F.Mask" "F.Paste")
			(net "USB3_01_MUX_FB_RXN")
		)
	)
	(footprint ""
		(layer "F.Cu")
		(at 61.595 -86.868 -90)
		(property "Reference" "R94"
			(at 0 0 270)
			(layer "F.SilkS")
			(hide yes)
			(effects
				(font
					(size 1.27 1.27)
				)
			)
		)
		(property "Value" ""
			(at 0 0 270)
			(layer "F.Fab")
			(effects
				(font
					(size 1.27 1.27)
				)
			)
		)
		(duplicate_pad_numbers_are_jumpers no)
		(fp_line
			(start -0.7874 0.4064)
			(end -0.7874 -0.4064)
			(stroke
				(width 0.1524)
				(type default)
			)
			(layer "F.SilkS")
		)
		(fp_line
			(start 0.7874 0.4064)
			(end -0.7874 0.4064)
			(stroke
				(width 0.1524)
				(type default)
			)
			(layer "F.SilkS")
		)
		(fp_line
			(start -0.7874 -0.4064)
			(end 0.7874 -0.4064)
			(stroke
				(width 0.1524)
				(type default)
			)
			(layer "F.SilkS")
		)
		(fp_line
			(start 0.7874 -0.4064)
			(end 0.7874 0.4064)
			(stroke
				(width 0.1524)
				(type default)
			)
			(layer "F.SilkS")
		)
		(fp_line
			(start -0.67945 0.3048)
			(end -0.67945 -0.305054)
			(stroke
				(width 0.1)
				(type default)
			)
			(layer "F.Fab")
		)
		(fp_line
			(start -0.12065 0.3048)
			(end -0.67945 0.3048)
			(stroke
				(width 0.1)
				(type default)
			)
			(layer "F.Fab")
		)
		(fp_line
			(start 0.120396 0.3048)
			(end 0.120396 0.2794)
			(stroke
				(width 0.1)
				(type default)
			)
			(layer "F.Fab")
		)
		(fp_line
			(start 0.67945 0.3048)
			(end 0.120396 0.3048)
			(stroke
				(width 0.1)
				(type default)
			)
			(layer "F.Fab")
		)
		(fp_line
			(start -0.12065 0.2794)
			(end -0.12065 0.3048)
			(stroke
				(width 0.1)
				(type default)
			)
			(layer "F.Fab")
		)
		(fp_line
			(start 0.120396 0.2794)
			(end -0.12065 0.2794)
			(stroke
				(width 0.1)
				(type default)
			)
			(layer "F.Fab")
		)
		(fp_line
			(start -0.12065 -0.2794)
			(end 0.12065 -0.2794)
			(stroke
				(width 0.1)
				(type default)
			)
			(layer "F.Fab")
		)
		(fp_line
			(start 0.12065 -0.2794)
			(end 0.12065 -0.3048)
			(stroke
				(width 0.1)
				(type default)
			)
			(layer "F.Fab")
		)
		(fp_line
			(start 0.12065 -0.3048)
			(end 0.67945 -0.3048)
			(stroke
				(width 0.1)
				(type default)
			)
			(layer "F.Fab")
		)
		(fp_line
			(start 0.67945 -0.3048)
			(end 0.67945 0.3048)
			(stroke
				(width 0.1)
				(type default)
			)
			(layer "F.Fab")
		)
		(fp_line
			(start -0.67945 -0.305054)
			(end -0.12065 -0.305054)
			(stroke
				(width 0.1)
				(type default)
			)
			(layer "F.Fab")
		)
		(fp_line
			(start -0.12065 -0.305054)
			(end -0.12065 -0.2794)
			(stroke
				(width 0.1)
				(type default)
			)
			(layer "F.Fab")
		)
		(pad "1" smd circle
			(at -0.40005 0 270)
			(size 0 0)
			(layers "F.Cu" "F.Mask" "F.Paste")
			(net "SPI_BMC_BOOT_MOSI")
		)
		(pad "2" smd circle
			(at 0.40005 0 270)
			(size 0 0)
			(layers "F.Cu" "F.Mask" "F.Paste")
			(net "GND")
		)
	)
	(footprint ""
		(layer "F.Cu")
		(at 76.708 -14.478)
		(property "Reference" "C29"
			(at 0 0 0)
			(layer "F.SilkS")
			(hide yes)
			(effects
				(font
					(size 1.27 1.27)
				)
			)
		)
		(property "Value" ""
			(at 0 0 0)
			(layer "F.Fab")
			(effects
				(font
					(size 1.27 1.27)
				)
			)
		)
		(duplicate_pad_numbers_are_jumpers no)
		(fp_line
			(start -0.7874 -0.4064)
			(end 0.7874 -0.4064)
			(stroke
				(width 0.1524)
				(type default)
			)
			(layer "F.SilkS")
		)
		(fp_line
			(start -0.7874 0.4064)
			(end -0.7874 -0.4064)
			(stroke
				(width 0.1524)
				(type default)
			)
			(layer "F.SilkS")
		)
		(fp_line
			(start 0.7874 -0.4064)
			(end 0.7874 0.4064)
			(stroke
				(width 0.1524)
				(type default)
			)
			(layer "F.SilkS")
		)
		(fp_line
			(start 0.7874 0.4064)
			(end -0.7874 0.4064)
			(stroke
				(width 0.1524)
				(type default)
			)
			(layer "F.SilkS")
		)
		(fp_line
			(start -0.67945 -0.305054)
			(end -0.12065 -0.305054)
			(stroke
				(width 0.1)
				(type default)
			)
			(layer "F.Fab")
		)
		(fp_line
			(start -0.67945 0.3048)
			(end -0.67945 -0.305054)
			(stroke
				(width 0.1)
				(type default)
			)
			(layer "F.Fab")
		)
		(fp_line
			(start -0.12065 -0.305054)
			(end -0.12065 -0.2794)
			(stroke
				(width 0.1)
				(type default)
			)
			(layer "F.Fab")
		)
		(fp_line
			(start -0.12065 -0.2794)
			(end 0.12065 -0.2794)
			(stroke
				(width 0.1)
				(type default)
			)
			(layer "F.Fab")
		)
		(fp_line
			(start -0.12065 0.2794)
			(end -0.12065 0.3048)
			(stroke
				(width 0.1)
				(type default)
			)
			(layer "F.Fab")
		)
		(fp_line
			(start -0.12065 0.3048)
			(end -0.67945 0.3048)
			(stroke
				(width 0.1)
				(type default)
			)
			(layer "F.Fab")
		)
		(fp_line
			(start 0.120396 0.2794)
			(end -0.12065 0.2794)
			(stroke
				(width 0.1)
				(type default)
			)
			(layer "F.Fab")
		)
		(fp_line
			(start 0.120396 0.3048)
			(end 0.120396 0.2794)
			(stroke
				(width 0.1)
				(type default)
			)
			(layer "F.Fab")
		)
		(fp_line
			(start 0.12065 -0.3048)
			(end 0.67945 -0.3048)
			(stroke
				(width 0.1)
				(type default)
			)
			(layer "F.Fab")
		)
		(fp_line
			(start 0.12065 -0.2794)
			(end 0.12065 -0.3048)
			(stroke
				(width 0.1)
				(type default)
			)
			(layer "F.Fab")
		)
		(fp_line
			(start 0.67945 -0.3048)
			(end 0.67945 0.3048)
			(stroke
				(width 0.1)
				(type default)
			)
			(layer "F.Fab")
		)
		(fp_line
			(start 0.67945 0.3048)
			(end 0.120396 0.3048)
			(stroke
				(width 0.1)
				(type default)
			)
			(layer "F.Fab")
		)
		(pad "1" smd circle
			(at -0.40005 0)
			(size 0 0)
			(layers "F.Cu" "F.Mask" "F.Paste")
			(net "P3V3_AUX")
		)
		(pad "2" smd circle
			(at 0.40005 0)
			(size 0 0)
			(layers "F.Cu" "F.Mask" "F.Paste")
			(net "GND")
		)
	)
)
